(kicad_pcb
	(version 20241229)
	(generator "pcbnew")
	(generator_version "9.0")
	(general
		(thickness 1.711)
		(legacy_teardrops no)
	)
	(paper "A4")
	(title_block
		(title "Antmicro Baseboard for Jetson AGX Thor")
		(date "2026-02-18")
		(rev "1.1.0")
		(company "Antmicro Ltd")
		(comment 1 "www.antmicro.com")
		(comment 9 "footprints 875-878 of 1170")
	)
	(layers
		(0 "F.Cu" signal)
		(4 "In1.Cu" signal)
		(6 "In2.Cu" signal)
		(8 "In3.Cu" signal)
		(10 "In4.Cu" jumper)
		(12 "In5.Cu" signal)
		(14 "In6.Cu" signal)
		(16 "In7.Cu" signal)
		(18 "In8.Cu" signal)
		(2 "B.Cu" signal)
		(9 "F.Adhes" user "F.Adhesive")
		(11 "B.Adhes" user "B.Adhesive")
		(13 "F.Paste" user)
		(15 "B.Paste" user)
		(5 "F.SilkS" user "F.Silkscreen")
		(7 "B.SilkS" user "B.Silkscreen")
		(1 "F.Mask" user)
		(3 "B.Mask" user)
		(17 "Dwgs.User" user "User.Drawings")
		(19 "Cmts.User" user "User.Comments")
		(21 "Eco1.User" user "User.Eco1")
		(23 "Eco2.User" user "User.Eco2")
		(25 "Edge.Cuts" user)
		(27 "Margin" user)
		(31 "F.CrtYd" user "F.Courtyard")
		(29 "B.CrtYd" user "B.Courtyard")
		(35 "F.Fab" user)
		(33 "B.Fab" user)
	)
	(footprint "antmicro-footprints:Conn_JST_SH_1x4_SM04B-SRSS-TB-LF-SN"
		(locked yes)
		(layer "B.Cu")
		(at 139.13 56.86)
		(property "Reference" "J16"
			(at 3.57 -0.86 270)
			(layer "B.SilkS")
			(effects
				(font
					(size 0.7 0.7)
					(thickness 0.15)
				)
				(justify right top mirror)
			)
		)
		(property "Value" "JST_SH_1x4_SM04B-SRSS-TB-LF-SN"
			(at -4 -3.88 0)
			(layer "B.Fab")
			(effects
				(font
					(size 0.7 0.7)
					(thickness 0.15)
				)
				(justify right top mirror)
			)
		)
		(property "Datasheet" "https://www.jst-mfg.com/product/pdf/eng/eSH.pdf"
			(at 0 0 0)
			(layer "B.Fab")
			(hide yes)
			(effects
				(font
					(size 1.27 1.27)
					(thickness 0.15)
				)
				(justify mirror)
			)
		)
		(property "Description" "Pin Header, Right Angle, Wire-to-Board, 1 mm, 1 Rows, 4 Contacts, Surface Mount Right Angle, SH"
			(at 0 0 0)
			(layer "B.Fab")
			(hide yes)
			(effects
				(font
					(size 1.27 1.27)
					(thickness 0.15)
				)
				(justify mirror)
			)
		)
		(property "MPN" "SM04B-SRSS-TB(LF)(SN)"
			(at 0 0 180)
			(unlocked yes)
			(layer "B.Fab")
			(hide yes)
			(effects
				(font
					(size 1 1)
					(thickness 0.15)
				)
				(justify mirror)
			)
		)
		(property "Manufacturer" "JST Automotive Connectors"
			(at 0 0 180)
			(unlocked yes)
			(layer "B.Fab")
			(hide yes)
			(effects
				(font
					(size 1 1)
					(thickness 0.15)
				)
				(justify mirror)
			)
		)
		(property "Author" "Antmicro"
			(at 0 0 180)
			(unlocked yes)
			(layer "B.Fab")
			(hide yes)
			(effects
				(font
					(size 1 1)
					(thickness 0.15)
				)
				(justify mirror)
			)
		)
		(property "License" "Apache-2.0"
			(at 0 0 180)
			(unlocked yes)
			(layer "B.Fab")
			(hide yes)
			(effects
				(font
					(size 1 1)
					(thickness 0.15)
				)
				(justify mirror)
			)
		)
		(sheetname "/Peripherals/")
		(sheetfile "peripherals.kicad_sch")
		(attr smd)
		(fp_line
			(start -3.2 2)
			(end -3.2 -0.6)
			(stroke
				(width 0.15)
				(type solid)
			)
			(layer "B.SilkS")
		)
		(fp_line
			(start -2 -2.6)
			(end 2 -2.6)
			(stroke
				(width 0.15)
				(type solid)
			)
			(layer "B.SilkS")
		)
		(fp_line
			(start -2 2)
			(end -3.2 2)
			(stroke
				(width 0.15)
				(type solid)
			)
			(layer "B.SilkS")
		)
		(fp_line
			(start 2 2)
			(end 3.2 2)
			(stroke
				(width 0.15)
				(type solid)
			)
			(layer "B.SilkS")
		)
		(fp_line
			(start 3.2 2)
			(end 3.2 -0.6)
			(stroke
				(width 0.15)
				(type solid)
			)
			(layer "B.SilkS")
		)
		(fp_circle
			(center -2.1 2.5)
			(end -2.05 2.5)
			(stroke
				(width 0.15)
				(type solid)
			)
			(fill yes)
			(layer "B.SilkS")
		)
		(fp_rect
			(start -3.65 3.14)
			(end 3.65 -2.9)
			(stroke
				(width 0.05)
				(type solid)
			)
			(fill no)
			(layer "B.CrtYd")
		)
		(fp_rect
			(start -3 2.475)
			(end 3 -2.475)
			(stroke
				(width 0.15)
				(type solid)
			)
			(fill no)
			(layer "B.Fab")
		)
		(fp_text user "Author: Antmicro"
			(at -4 -7.08 0)
			(layer "B.Fab")
			(effects
				(font
					(size 0.7 0.7)
					(thickness 0.15)
				)
				(justify right top mirror)
			)
		)
		(fp_text user "License: Apache-2.0"
			(at -4 -5.88 0)
			(layer "B.Fab")
			(effects
				(font
					(size 0.7 0.7)
					(thickness 0.15)
				)
				(justify right top mirror)
			)
		)
		(fp_text user "${REFERENCE}"
			(at -4 -8.28 0)
			(layer "B.Fab")
			(effects
				(font
					(size 0.7 0.7)
					(thickness 0.15)
				)
				(justify right top mirror)
			)
		)
		(pad "1" smd roundrect
			(at -1.5 2.12 180)
			(size 0.6 1.55)
			(layers "B.Cu" "B.Mask" "B.Paste")
			(roundrect_rratio 0.25)
			(net 1 "GND")
			(pintype "passive")
		)
		(pad "2" smd roundrect
			(at -0.5 2.12 180)
			(size 0.6 1.55)
			(layers "B.Cu" "B.Mask" "B.Paste")
			(roundrect_rratio 0.25)
			(net 838 "/Peripherals/I2C_CONN1_3V3")
			(pintype "passive")
		)
		(pad "3" smd roundrect
			(at 0.5 2.12 180)
			(size 0.6 1.55)
			(layers "B.Cu" "B.Mask" "B.Paste")
			(roundrect_rratio 0.25)
			(net 43 "/Peripherals/I2C_{CONN}.SDA")
			(pintype "passive")
		)
		(pad "4" smd roundrect
			(at 1.5 2.12 180)
			(size 0.6 1.55)
			(layers "B.Cu" "B.Mask" "B.Paste")
			(roundrect_rratio 0.25)
			(net 42 "/Peripherals/I2C_{CONN}.SCL")
			(pintype "passive")
		)
		(pad "MP" smd roundrect
			(at -2.8 -1.755)
			(size 1.2 1.8)
			(layers "B.Cu" "B.Mask" "B.Paste")
			(roundrect_rratio 0.25)
			(net 1 "GND")
			(pintype "passive")
		)
		(pad "MP" smd roundrect
			(at 2.8 -1.755)
			(size 1.2 1.8)
			(layers "B.Cu" "B.Mask" "B.Paste")
			(roundrect_rratio 0.25)
			(net 1 "GND")
			(pintype "passive")
		)
	)
	(footprint "antmicro-footprints:Vishay_PowerPAK_1212-8_Single"
		(layer "B.Cu")
		(at 183.08 88.537 90)
		(descr "PowerPAK 1212-8 Single")
		(tags "Vishay PowerPAK 1212-8 Single")
		(property "Reference" "Q5"
			(at 0.637 1.92 90)
			(layer "B.SilkS")
			(effects
				(font
					(size 0.7 0.7)
					(thickness 0.15)
				)
				(justify right top mirror)
			)
		)
		(property "Value" "SISS05DN-T1-GE3"
			(at 0 -2.7 90)
			(layer "B.Fab")
			(effects
				(font
					(size 0.7 0.7)
					(thickness 0.15)
				)
				(justify right top mirror)
			)
		)
		(property "Datasheet" "https://www.vishay.com/docs/77029/siss05dn.pdf"
			(at 0 0 90)
			(layer "B.Fab")
			(hide yes)
			(effects
				(font
					(size 1.27 1.27)
					(thickness 0.15)
				)
				(justify mirror)
			)
		)
		(property "Description" "Power MOSFET, P Channel, 30 V, 108 A, 0.0035 ohm, PowerPAK 1212, Surface Mount"
			(at 0 0 90)
			(layer "B.Fab")
			(hide yes)
			(effects
				(font
					(size 1.27 1.27)
					(thickness 0.15)
				)
				(justify mirror)
			)
		)
		(property "MPN" "SISS05DN-T1-GE3"
			(at 0 0 270)
			(unlocked yes)
			(layer "B.Fab")
			(hide yes)
			(effects
				(font
					(size 1 1)
					(thickness 0.15)
				)
				(justify mirror)
			)
		)
		(property "Manufacturer" "Vishay"
			(at 0 0 270)
			(unlocked yes)
			(layer "B.Fab")
			(hide yes)
			(effects
				(font
					(size 1 1)
					(thickness 0.15)
				)
				(justify mirror)
			)
		)
		(property "Author" "Antmicro"
			(at 0 0 270)
			(unlocked yes)
			(layer "B.Fab")
			(hide yes)
			(effects
				(font
					(size 1 1)
					(thickness 0.15)
				)
				(justify mirror)
			)
		)
		(property "License" "Apache-2.0"
			(at 0 0 270)
			(unlocked yes)
			(layer "B.Fab")
			(hide yes)
			(effects
				(font
					(size 1 1)
					(thickness 0.15)
				)
				(justify mirror)
			)
		)
		(sheetname "/Power/")
		(sheetfile "power.kicad_sch")
		(attr smd exclude_from_pos_files exclude_from_bom dnp)
		(fp_line
			(start -1.635 -1.634)
			(end 1.634 -1.634)
			(stroke
				(width 0.15)
				(type solid)
			)
			(layer "B.SilkS")
		)
		(fp_line
			(start 1.634 -1.3)
			(end 1.634 -1.634)
			(stroke
				(width 0.15)
				(type solid)
			)
			(layer "B.SilkS")
		)
		(fp_line
			(start -1.635 -1.3)
			(end -1.635 -1.634)
			(stroke
				(width 0.15)
				(type solid)
			)
			(layer "B.SilkS")
		)
		(fp_line
			(start 1.648 1.651)
			(end 1.648 1.317)
			(stroke
				(width 0.15)
				(type solid)
			)
			(layer "B.SilkS")
		)
		(fp_line
			(start -1.651 1.651)
			(end -1.651 1.317)
			(stroke
				(width 0.15)
				(type solid)
			)
			(layer "B.SilkS")
		)
		(fp_line
			(start -1.651 1.651)
			(end 1.648 1.651)
			(stroke
				(width 0.15)
				(type solid)
			)
			(layer "B.SilkS")
		)
		(fp_circle
			(center -1.9 1.4)
			(end -1.85 1.4)
			(stroke
				(width 0.15)
				(type solid)
			)
			(fill yes)
			(layer "B.SilkS")
		)
		(fp_rect
			(start -2 1.8)
			(end 2 -1.798)
			(stroke
				(width 0.05)
				(type solid)
			)
			(fill no)
			(layer "B.CrtYd")
		)
		(fp_line
			(start -1.6425 1.4175)
			(end -1.4175 1.6425)
			(stroke
				(width 0.15)
				(type solid)
			)
			(layer "B.Fab")
		)
		(fp_rect
			(start -1.651 1.651)
			(end 1.648 -1.648)
			(stroke
				(width 0.15)
				(type solid)
			)
			(fill no)
			(layer "B.Fab")
		)
		(fp_text user "License: Apache-2.0"
			(at -8 -7.1 90)
			(layer "B.Fab")
			(effects
				(font
					(size 0.7 0.7)
					(thickness 0.15)
				)
				(justify right top mirror)
			)
		)
		(fp_text user "${REFERENCE}"
			(at -8 -4.7 90)
			(layer "B.Fab")
			(effects
				(font
					(size 0.7 0.7)
					(thickness 0.15)
				)
				(justify right top mirror)
			)
		)
		(fp_text user "Author: Antmicro"
			(at -8 -5.9 90)
			(layer "B.Fab")
			(effects
				(font
					(size 0.7 0.7)
					(thickness 0.15)
				)
				(justify right top mirror)
			)
		)
		(pad "1" smd rect
			(at -1.436 0.99 90)
			(size 0.99 0.405)
			(layers "B.Cu" "B.Mask" "B.Paste")
			(net 13 "VCC")
			(pinfunction "S")
			(pintype "passive")
		)
		(pad "2" smd rect
			(at -1.436 0.332 90)
			(size 0.99 0.405)
			(layers "B.Cu" "B.Mask" "B.Paste")
			(net 13 "VCC")
			(pinfunction "S")
			(pintype "passive")
		)
		(pad "3" smd rect
			(at -1.436 -0.33 90)
			(size 0.99 0.405)
			(layers "B.Cu" "B.Mask" "B.Paste")
			(net 13 "VCC")
			(pinfunction "S")
			(pintype "passive")
		)
		(pad "4" smd rect
			(at -1.436 -0.988 90)
			(size 0.99 0.405)
			(layers "B.Cu" "B.Mask" "B.Paste")
			(net 1200 "Net-(Q5-G)")
			(pinfunction "G")
			(pintype "input")
		)
		(pad "5" smd custom
			(at 0.557 0 90)
			(size 1.725 2.235)
			(layers "B.Cu" "B.Mask" "B.Paste")
			(net 522 "/Power/USBPD1_HV")
			(pinfunction "D")
			(pintype "passive")
			(zone_connect 2)
			(options
				(clearance outline)
				(anchor rect)
			)
			(primitives
				(gr_poly
					(pts
						(xy 0.8625 -0.1275) (xy 0.8625 0.1275) (xy 1.3725 0.1275) (xy 1.3725 0.5325) (xy 0.8625 0.5325)
						(xy 0.8625 0.7875) (xy 1.3725 0.7875) (xy 1.3725 1.195) (xy 0.6125 1.195) (xy 0.6125 -1.195) (xy 1.3725 -1.195)
						(xy 1.3725 -0.7875) (xy 0.8625 -0.7875) (xy 0.8625 -0.5325) (xy 1.3725 -0.5325) (xy 1.3725 -0.1275)
					)
					(width 0)
					(fill yes)
				)
			)
		)
	)
	(footprint "antmicro-footprints:C_0402_1005Metric"
		(layer "B.Cu")
		(at 89.9 78.9 -90)
		(descr "Capacitor SMD 0402")
		(tags "capacitor SMD 0402")
		(property "Reference" "C365"
			(at -1.9 -1.5 90)
			(layer "B.SilkS")
			(effects
				(font
					(size 0.7 0.7)
					(thickness 0.15)
				)
				(justify left bottom mirror)
			)
		)
		(property "Value" "C_1u_25V_0402"
			(at -1.022927 -2.155213 90)
			(layer "B.Fab")
			(effects
				(font
					(size 0.7 0.7)
					(thickness 0.15)
				)
				(justify left bottom mirror)
			)
		)
		(property "Datasheet" "https://www.murata.com/products/productdetail?partno=GRM155R61E105KE11%23"
			(at 0 0 90)
			(layer "B.Fab")
			(hide yes)
			(effects
				(font
					(size 1.27 1.27)
					(thickness 0.15)
				)
				(justify mirror)
			)
		)
		(property "Description" "SMD Multilayer Ceramic Capacitor, 1 µF, 25 V, 0402 [1005 Metric], ± 10%, X5R, GRM Series"
			(at 0 0 90)
			(layer "B.Fab")
			(hide yes)
			(effects
				(font
					(size 1.27 1.27)
					(thickness 0.15)
				)
				(justify mirror)
			)
		)
		(property "MPN" "GRM155R61E105KE11J"
			(at 0 0 90)
			(unlocked yes)
			(layer "B.Fab")
			(hide yes)
			(effects
				(font
					(size 1 1)
					(thickness 0.15)
				)
				(justify mirror)
			)
		)
		(property "Manufacturer" "Murata"
			(at 0 0 90)
			(unlocked yes)
			(layer "B.Fab")
			(hide yes)
			(effects
				(font
					(size 1 1)
					(thickness 0.15)
				)
				(justify mirror)
			)
		)
		(property "License" "Apache-2.0"
			(at 0 0 90)
			(unlocked yes)
			(layer "B.Fab")
			(hide yes)
			(effects
				(font
					(size 1 1)
					(thickness 0.15)
				)
				(justify mirror)
			)
		)
		(property "Author" "Antmicro"
			(at 0 0 90)
			(unlocked yes)
			(layer "B.Fab")
			(hide yes)
			(effects
				(font
					(size 1 1)
					(thickness 0.15)
				)
				(justify mirror)
			)
		)
		(property "Val" "1u"
			(at 0 0 90)
			(unlocked yes)
			(layer "B.Fab")
			(hide yes)
			(effects
				(font
					(size 1 1)
					(thickness 0.15)
				)
				(justify mirror)
			)
		)
		(property "Voltage" "25V"
			(at 0 0 90)
			(unlocked yes)
			(layer "B.Fab")
			(hide yes)
			(effects
				(font
					(size 1 1)
					(thickness 0.15)
				)
				(justify mirror)
			)
		)
		(property "Dielectric" "X5R"
			(at 0 0 90)
			(unlocked yes)
			(layer "B.Fab")
			(hide yes)
			(effects
				(font
					(size 1 1)
					(thickness 0.15)
				)
				(justify mirror)
			)
		)
		(sheetname "/SoM_Power/")
		(sheetfile "som_power.kicad_sch")
		(attr smd)
		(fp_poly
			(pts
				(xy -0.925 0.47) (xy 0.925 0.47) (xy 0.925 -0.47) (xy -0.925 -0.47)
			)
			(stroke
				(width 0.05)
				(type default)
			)
			(fill no)
			(layer "B.CrtYd")
		)
		(fp_line
			(start -0.494 0.25)
			(end 0.504 0.25)
			(stroke
				(width 0.15)
				(type solid)
			)
			(layer "B.Fab")
		)
		(fp_line
			(start 0.504 0.25)
			(end 0.504 -0.248)
			(stroke
				(width 0.15)
				(type solid)
			)
			(layer "B.Fab")
		)
		(fp_line
			(start -0.494 -0.248)
			(end -0.494 0.25)
			(stroke
				(width 0.15)
				(type solid)
			)
			(layer "B.Fab")
		)
		(fp_line
			(start 0.504 -0.248)
			(end -0.494 -0.248)
			(stroke
				(width 0.15)
				(type solid)
			)
			(layer "B.Fab")
		)
		(fp_text user "${REFERENCE}"
			(at -0.939 -4.599 90)
			(layer "B.Fab")
			(effects
				(font
					(size 0.7 0.7)
					(thickness 0.15)
				)
				(justify left bottom mirror)
			)
		)
		(fp_text user "License: Apache-2.0"
			(at -0.939 -5.799 90)
			(layer "B.Fab")
			(effects
				(font
					(size 0.7 0.7)
					(thickness 0.15)
				)
				(justify left bottom mirror)
			)
		)
		(fp_text user "Author: Antmicro"
			(at -0.939 -3.399 90)
			(layer "B.Fab")
			(effects
				(font
					(size 0.7 0.7)
					(thickness 0.15)
				)
				(justify left bottom mirror)
			)
		)
		(pad "1" smd roundrect
			(at -0.48 0 270)
			(size 0.59 0.64)
			(layers "B.Cu" "B.Mask" "B.Paste")
			(roundrect_rratio 0.25)
			(net 1 "GND")
			(pintype "passive")
		)
		(pad "2" smd roundrect
			(at 0.48 0 270)
			(size 0.59 0.64)
			(layers "B.Cu" "B.Mask" "B.Paste")
			(roundrect_rratio 0.25)
			(net 12 "SYS_VIN_HV")
			(pintype "passive")
		)
	)
	(footprint "antmicro-footprints:R_0402_1005Metric"
		(layer "B.Cu")
		(at 111.12 121.6)
		(descr "Resistor SMD 0402")
		(tags "resistor SMD 0402")
		(property "Reference" "R219"
			(at -3.72 -0.39 0)
			(layer "B.SilkS")
			(effects
				(font
					(size 0.7 0.7)
					(thickness 0.15)
				)
				(justify right top mirror)
			)
		)
		(property "Value" "R_0R_0402"
			(at -1.011843 -1.772047 0)
			(layer "B.Fab")
			(effects
				(font
					(size 0.7 0.7)
					(thickness 0.15)
				)
				(justify right top mirror)
			)
		)
		(property "Datasheet" "https://industrial.panasonic.com/cdbs/www-data/pdf/RDA0000/AOA0000C301.pdf"
			(at 0 0 0)
			(layer "B.Fab")
			(hide yes)
			(effects
				(font
					(size 1.27 1.27)
					(thickness 0.15)
				)
				(justify mirror)
			)
		)
		(property "Description" "SMD Chip Resistor, Jumper, 0 ohm, 100 mW, 0402 [1005 Metric], Thick Film, General Purpose"
			(at 0 0 0)
			(layer "B.Fab")
			(hide yes)
			(effects
				(font
					(size 1.27 1.27)
					(thickness 0.15)
				)
				(justify mirror)
			)
		)
		(property "MPN" "ERJ2GE0R00X"
			(at 0 0 180)
			(unlocked yes)
			(layer "B.Fab")
			(hide yes)
			(effects
				(font
					(size 1 1)
					(thickness 0.15)
				)
				(justify mirror)
			)
		)
		(property "Manufacturer" "Panasonic"
			(at 0 0 180)
			(unlocked yes)
			(layer "B.Fab")
			(hide yes)
			(effects
				(font
					(size 1 1)
					(thickness 0.15)
				)
				(justify mirror)
			)
		)
		(property "License" "Apache-2.0"
			(at 0 0 180)
			(unlocked yes)
			(layer "B.Fab")
			(hide yes)
			(effects
				(font
					(size 1 1)
					(thickness 0.15)
				)
				(justify mirror)
			)
		)
		(property "Val" "0R"
			(at 0 0 180)
			(unlocked yes)
			(layer "B.Fab")
			(hide yes)
			(effects
				(font
					(size 1 1)
					(thickness 0.15)
				)
				(justify mirror)
			)
		)
		(property "Tolerance" "~"
			(at 0 0 180)
			(unlocked yes)
			(layer "B.Fab")
			(hide yes)
			(effects
				(font
					(size 1 1)
					(thickness 0.15)
				)
				(justify mirror)
			)
		)
		(property "Current" "1A"
			(at 0 0 180)
			(unlocked yes)
			(layer "B.Fab")
			(hide yes)
			(effects
				(font
					(size 1 1)
					(thickness 0.15)
				)
				(justify mirror)
			)
		)
		(property "Author" "Antmicro"
			(at 0 0 180)
			(unlocked yes)
			(layer "B.Fab")
			(hide yes)
			(effects
				(font
					(size 1 1)
					(thickness 0.15)
				)
				(justify mirror)
			)
		)
		(property "Public" "False"
			(at 0 0 180)
			(unlocked yes)
			(layer "B.Fab")
			(hide yes)
			(effects
				(font
					(size 1 1)
					(thickness 0.15)
				)
				(justify mirror)
			)
		)
		(sheetname "/M.2/")
		(sheetfile "m2.kicad_sch")
		(attr smd)
		(fp_rect
			(start -0.925 0.47)
			(end 0.925 -0.47)
			(stroke
				(width 0.05)
				(type default)
			)
			(fill no)
			(layer "B.CrtYd")
		)
		(fp_rect
			(start -0.5 0.25)
			(end 0.5 -0.25)
			(stroke
				(width 0.15)
				(type solid)
			)
			(fill no)
			(layer "B.Fab")
		)
		(fp_text user "License: Apache-2.0"
			(at -0.95 -5.169 0)
			(layer "B.Fab")
			(effects
				(font
					(size 0.7 0.7)
					(thickness 0.15)
				)
				(justify right top mirror)
			)
		)
		(fp_text user "${REFERENCE}"
			(at -0.95 -3.168 0)
			(layer "B.Fab")
			(effects
				(font
					(size 0.7 0.7)
					(thickness 0.15)
				)
				(justify right top mirror)
			)
		)
		(fp_text user "Author: Antmicro"
			(at -0.95 -4.169 0)
			(layer "B.Fab")
			(effects
				(font
					(size 0.7 0.7)
					(thickness 0.15)
				)
				(justify right top mirror)
			)
		)
		(pad "1" smd roundrect
			(at -0.48 0)
			(size 0.59 0.64)
			(layers "B.Cu" "B.Mask" "B.Paste")
			(roundrect_rratio 0.25)
			(net 642 "/M.2/USB3.D-")
			(pintype "passive")
		)
		(pad "2" smd roundrect
			(at 0.48 0)
			(size 0.59 0.64)
			(layers "B.Cu" "B.Mask" "B.Paste")
			(roundrect_rratio 0.25)
			(net 259 "/M.2/WIFI_BT_USB_D_N")
			(pintype "passive")
		)
	)
)
